# T6G (Grand Teton) — schematic netlist excerpt (pin names and nets, part order shuffled) for the footprints in the layout excerpt that follows; sources: Cadence DE-HDL packaged netlist, KiCad conversion of 04192023_DAF0TMB3IC0_F0TG_MB_C_brd_V02_OCP.brd

PR3994  Q_RES  0 5% CHIP  pkg 0402LF  page 264 : A = HSC_D_OC_4 ; B = HSC_D_OC_R
R3322  Q_RES  1K 1% CHIP  pkg 0402LF  page 233 : A = P3V3_AUX ; B = CLK_GEN2_GPU_FPGA_OE_R2_N
C822  Q_CAP_DIFFBUS  DIFF BUS_0.22UF 6.3V 20% X6S  pkg C0201  page 65 : \1\ = P5E_CPU1_P0_TX_C_DN<7> ; \2\ = P5E_CPU1_P0_TX_DN<7>

(kicad_pcb
	(version 20260206)
	(generator "pcbnew")
	(generator_version "10.0")
	(general
		(thickness 1.6)
		(legacy_teardrops no)
	)
	(paper "A4")
	(title_block
		(title "04192023_DAF0TMB3IC0_F0TG_MB_C_brd_V02_OCP.brd")
		(comment 1 "Grand Teton / footprints 433-435 of 8354")
	)
	(layers
		(0 "F.Cu" signal "TOP")
		(4 "In1.Cu" signal "GND")
		(6 "In2.Cu" signal "IN1")
		(8 "In3.Cu" signal "GND1")
		(10 "In4.Cu" signal "IN2")
		(12 "In5.Cu" signal "GND2")
		(14 "In6.Cu" signal "IN3")
		(16 "In7.Cu" signal "GND3")
		(18 "In8.Cu" signal "VCC")
		(20 "In9.Cu" signal "VCC1")
		(22 "In10.Cu" signal "GND4")
		(24 "In11.Cu" signal "IN4")
		(26 "In12.Cu" signal "GND5")
		(28 "In13.Cu" signal "IN5")
		(30 "In14.Cu" signal "GND6")
		(32 "In15.Cu" signal "IN6")
		(34 "In16.Cu" signal "GND7")
		(2 "B.Cu" signal "BOTTOM")
		(9 "F.Adhes" user "F.Adhesive")
		(11 "B.Adhes" user "B.Adhesive")
		(13 "F.Paste" user "Package Geometry/Pastemask Top")
		(15 "B.Paste" user "Package Geometry/Pastemask Bottom")
		(5 "F.SilkS" user "Ref Des/Silkscreen Top")
		(7 "B.SilkS" user "Ref Des/Silkscreen Bottom")
		(1 "F.Mask" user "Board Geometry/Soldermask Top")
		(3 "B.Mask" user "Board Geometry/Soldermask Bottom")
		(17 "Dwgs.User" user "User.Drawings")
		(19 "Cmts.User" user "User.Comments")
		(21 "Eco1.User" user "User.Eco1")
		(23 "Eco2.User" user "User.Eco2")
		(25 "Edge.Cuts" user "Board Geometry/Outline")
		(27 "Margin" user)
		(31 "F.CrtYd" user "Package Geometry/Place Bound Top")
		(29 "B.CrtYd" user "Package Geometry/Place Bound Bottom")
		(35 "F.Fab" user "Ref Des/Assembly Top")
		(33 "B.Fab" user "Ref Des/Assembly Bottom")
	)
	(footprint ""
		(layer "F.Cu")
		(at 236.7661 -400.871182)
		(property "Reference" "PR3994"
			(at 0 0 0)
			(layer "F.SilkS")
			(hide yes)
			(effects
				(font
					(size 1.27 1.27)
				)
			)
		)
		(property "Value" ""
			(at 0 0 0)
			(layer "F.Fab")
			(effects
				(font
					(size 1.27 1.27)
				)
			)
		)
		(duplicate_pad_numbers_are_jumpers no)
		(fp_line
			(start -0.7874 -0.4064)
			(end 0.7874 -0.4064)
			(stroke
				(width 0.1524)
				(type default)
			)
			(layer "F.SilkS")
		)
		(fp_line
			(start -0.7874 0.4064)
			(end -0.7874 -0.4064)
			(stroke
				(width 0.1524)
				(type default)
			)
			(layer "F.SilkS")
		)
		(fp_line
			(start 0.7874 -0.4064)
			(end 0.7874 0.4064)
			(stroke
				(width 0.1524)
				(type default)
			)
			(layer "F.SilkS")
		)
		(fp_line
			(start 0.7874 0.4064)
			(end -0.7874 0.4064)
			(stroke
				(width 0.1524)
				(type default)
			)
			(layer "F.SilkS")
		)
		(fp_line
			(start -0.67945 -0.305054)
			(end -0.12065 -0.305054)
			(stroke
				(width 0.1)
				(type default)
			)
			(layer "F.Fab")
		)
		(fp_line
			(start -0.67945 0.3048)
			(end -0.67945 -0.305054)
			(stroke
				(width 0.1)
				(type default)
			)
			(layer "F.Fab")
		)
		(fp_line
			(start -0.12065 -0.305054)
			(end -0.12065 -0.2794)
			(stroke
				(width 0.1)
				(type default)
			)
			(layer "F.Fab")
		)
		(fp_line
			(start -0.12065 -0.2794)
			(end 0.12065 -0.2794)
			(stroke
				(width 0.1)
				(type default)
			)
			(layer "F.Fab")
		)
		(fp_line
			(start -0.12065 0.2794)
			(end -0.12065 0.3048)
			(stroke
				(width 0.1)
				(type default)
			)
			(layer "F.Fab")
		)
		(fp_line
			(start -0.12065 0.3048)
			(end -0.67945 0.3048)
			(stroke
				(width 0.1)
				(type default)
			)
			(layer "F.Fab")
		)
		(fp_line
			(start 0.120396 0.2794)
			(end -0.12065 0.2794)
			(stroke
				(width 0.1)
				(type default)
			)
			(layer "F.Fab")
		)
		(fp_line
			(start 0.120396 0.3048)
			(end 0.120396 0.2794)
			(stroke
				(width 0.1)
				(type default)
			)
			(layer "F.Fab")
		)
		(fp_line
			(start 0.12065 -0.3048)
			(end 0.67945 -0.3048)
			(stroke
				(width 0.1)
				(type default)
			)
			(layer "F.Fab")
		)
		(fp_line
			(start 0.12065 -0.2794)
			(end 0.12065 -0.3048)
			(stroke
				(width 0.1)
				(type default)
			)
			(layer "F.Fab")
		)
		(fp_line
			(start 0.67945 -0.3048)
			(end 0.67945 0.3048)
			(stroke
				(width 0.1)
				(type default)
			)
			(layer "F.Fab")
		)
		(fp_line
			(start 0.67945 0.3048)
			(end 0.120396 0.3048)
			(stroke
				(width 0.1)
				(type default)
			)
			(layer "F.Fab")
		)
		(pad "1" smd circle
			(at -0.40005 0)
			(size 0 0)
			(layers "F.Cu" "F.Mask" "F.Paste")
			(net "HSC_D_OC_4")
		)
		(pad "2" smd circle
			(at 0.40005 0)
			(size 0 0)
			(layers "F.Cu" "F.Mask" "F.Paste")
			(net "HSC_D_OC_R")
		)
	)
	(footprint ""
		(layer "F.Cu")
		(at 55.816754 -375.49963 -90)
		(property "Reference" "C822"
			(at 0 0 270)
			(layer "F.SilkS")
			(hide yes)
			(effects
				(font
					(size 1.27 1.27)
				)
			)
		)
		(property "Value" ""
			(at 0 0 270)
			(layer "F.Fab")
			(effects
				(font
					(size 1.27 1.27)
				)
			)
		)
		(duplicate_pad_numbers_are_jumpers no)
		(fp_line
			(start -0.299974 0.150114)
			(end -0.299974 -0.150114)
			(stroke
				(width 0.1)
				(type default)
			)
			(layer "F.Fab")
		)
		(fp_line
			(start 0.299974 0.150114)
			(end -0.299974 0.150114)
			(stroke
				(width 0.1)
				(type default)
			)
			(layer "F.Fab")
		)
		(fp_line
			(start -0.299974 -0.150114)
			(end 0.299974 -0.150114)
			(stroke
				(width 0.1)
				(type default)
			)
			(layer "F.Fab")
		)
		(fp_line
			(start 0.299974 -0.150114)
			(end 0.299974 0.150114)
			(stroke
				(width 0.1)
				(type default)
			)
			(layer "F.Fab")
		)
		(pad "1" smd rect
			(at -0.2667 0 270)
			(size 0.3048 0.381)
			(layers "F.Cu" "F.Mask" "F.Paste")
			(net "P5E_CPU1_P0_TX_C_DN<7>")
		)
		(pad "2" smd rect
			(at 0.2667 0 270)
			(size 0.3048 0.381)
			(layers "F.Cu" "F.Mask" "F.Paste")
			(net "P5E_CPU1_P0_TX_DN<7>")
		)
	)
	(footprint ""
		(layer "F.Cu")
		(at 36.319968 -134.873238 180)
		(property "Reference" "R3322"
			(at 0 0 180)
			(layer "F.SilkS")
			(hide yes)
			(effects
				(font
					(size 1.27 1.27)
				)
			)
		)
		(property "Value" ""
			(at 0 0 180)
			(layer "F.Fab")
			(effects
				(font
					(size 1.27 1.27)
				)
			)
		)
		(duplicate_pad_numbers_are_jumpers no)
		(fp_line
			(start 0.7874 0.4064)
			(end -0.7874 0.4064)
			(stroke
				(width 0.1524)
				(type default)
			)
			(layer "F.SilkS")
		)
		(fp_line
			(start 0.7874 -0.4064)
			(end 0.7874 0.4064)
			(stroke
				(width 0.1524)
				(type default)
			)
			(layer "F.SilkS")
		)
		(fp_line
			(start -0.7874 0.4064)
			(end -0.7874 -0.4064)
			(stroke
				(width 0.1524)
				(type default)
			)
			(layer "F.SilkS")
		)
		(fp_line
			(start -0.7874 -0.4064)
			(end 0.7874 -0.4064)
			(stroke
				(width 0.1524)
				(type default)
			)
			(layer "F.SilkS")
		)
		(fp_line
			(start 0.67945 0.3048)
			(end 0.120396 0.3048)
			(stroke
				(width 0.1)
				(type default)
			)
			(layer "F.Fab")
		)
		(fp_line
			(start 0.67945 -0.3048)
			(end 0.67945 0.3048)
			(stroke
				(width 0.1)
				(type default)
			)
			(layer "F.Fab")
		)
		(fp_line
			(start 0.12065 -0.2794)
			(end 0.12065 -0.3048)
			(stroke
				(width 0.1)
				(type default)
			)
			(layer "F.Fab")
		)
		(fp_line
			(start 0.12065 -0.3048)
			(end 0.67945 -0.3048)
			(stroke
				(width 0.1)
				(type default)
			)
			(layer "F.Fab")
		)
		(fp_line
			(start 0.120396 0.3048)
			(end 0.120396 0.2794)
			(stroke
				(width 0.1)
				(type default)
			)
			(layer "F.Fab")
		)
		(fp_line
			(start 0.120396 0.2794)
			(end -0.12065 0.2794)
			(stroke
				(width 0.1)
				(type default)
			)
			(layer "F.Fab")
		)
		(fp_line
			(start -0.12065 0.3048)
			(end -0.67945 0.3048)
			(stroke
				(width 0.1)
				(type default)
			)
			(layer "F.Fab")
		)
		(fp_line
			(start -0.12065 0.2794)
			(end -0.12065 0.3048)
			(stroke
				(width 0.1)
				(type default)
			)
			(layer "F.Fab")
		)
		(fp_line
			(start -0.12065 -0.2794)
			(end 0.12065 -0.2794)
			(stroke
				(width 0.1)
				(type default)
			)
			(layer "F.Fab")
		)
		(fp_line
			(start -0.12065 -0.305054)
			(end -0.12065 -0.2794)
			(stroke
				(width 0.1)
				(type default)
			)
			(layer "F.Fab")
		)
		(fp_line
			(start -0.67945 0.3048)
			(end -0.67945 -0.305054)
			(stroke
				(width 0.1)
				(type default)
			)
			(layer "F.Fab")
		)
		(fp_line
			(start -0.67945 -0.305054)
			(end -0.12065 -0.305054)
			(stroke
				(width 0.1)
				(type default)
			)
			(layer "F.Fab")
		)
		(pad "1" smd circle
			(at -0.40005 0 180)
			(size 0 0)
			(layers "F.Cu" "F.Mask" "F.Paste")
			(net "P3V3_AUX")
		)
		(pad "2" smd circle
			(at 0.40005 0 180)
			(size 0 0)
			(layers "F.Cu" "F.Mask" "F.Paste")
			(net "CLK_GEN2_GPU_FPGA_OE_R2_N")
		)
	)
)
